(kicad_pcb
	(version 20260206)
	(generator "pcbnew")
	(generator_version "10.0")
	(general
		(thickness 1.6)
		(legacy_teardrops no)
	)
	(paper "A4")
	(title_block
		(title "pdpb — Lightning_PDPB_BRD.brd")
		(comment 1 "Lightning (Wiwynn / Facebook NVMe JBOF) / footprints 520-522 of 1140")
	)
	(layers
		(0 "F.Cu" signal "TOP")
		(4 "In1.Cu" signal "L2GND")
		(6 "In2.Cu" signal "L3")
		(8 "In3.Cu" signal "L4VCC")
		(10 "In4.Cu" signal "L5VCC")
		(12 "In5.Cu" signal "L6")
		(14 "In6.Cu" signal "L7GND")
		(2 "B.Cu" signal "BOTTOM")
		(9 "F.Adhes" user "F.Adhesive")
		(11 "B.Adhes" user "B.Adhesive")
		(13 "F.Paste" user "Package Geometry/Pastemask Top")
		(15 "B.Paste" user "Package Geometry/Pastemask Bottom")
		(5 "F.SilkS" user "Ref Des/Silkscreen Top")
		(7 "B.SilkS" user "Ref Des/Silkscreen Bottom")
		(1 "F.Mask" user "Board Geometry/Soldermask Top")
		(3 "B.Mask" user "Board Geometry/Soldermask Bottom")
		(17 "Dwgs.User" user "User.Drawings")
		(19 "Cmts.User" user "User.Comments")
		(21 "Eco1.User" user "User.Eco1")
		(23 "Eco2.User" user "User.Eco2")
		(25 "Edge.Cuts" user "Board Geometry/Outline")
		(27 "Margin" user)
		(31 "F.CrtYd" user "Package Geometry/Place Bound Top")
		(29 "B.CrtYd" user "Package Geometry/Place Bound Bottom")
		(35 "F.Fab" user "Ref Des/Assembly Top")
		(33 "B.Fab" user "Ref Des/Assembly Bottom")
	)
	(footprint ""
		(layer "F.Cu")
		(at 93.599 -312.801 180)
		(property "Reference" "C9425"
			(at 0 0 180)
			(layer "F.SilkS")
			(hide yes)
			(effects
				(font
					(size 1.27 1.27)
				)
			)
		)
		(property "Value" "SCD1U16V2KX-3GP"
			(at 1.1811 -2.7051 180)
			(unlocked yes)
			(layer "F.Fab")
			(hide yes)
			(effects
				(font
					(size 1.016 1.016)
					(thickness 0.1524)
				)
			)
		)
		(property "Device Type" "C402H22"
			(at 1.1811 -4.2291 180)
			(unlocked yes)
			(layer "F.Fab")
			(hide yes)
			(effects
				(font
					(size 1.016 1.016)
					(thickness 0.1524)
				)
			)
		)
		(duplicate_pad_numbers_are_jumpers no)
		(fp_rect
			(start -0.4318 0.9525)
			(end 0.4318 -0.9525)
			(stroke
				(width 0)
				(type default)
			)
			(fill no)
			(layer "F.CrtYd")
		)
		(fp_rect
			(start -0.4318 0.9525)
			(end 0.4318 -0.9525)
			(stroke
				(width 0)
				(type default)
			)
			(fill no)
			(layer "F.Fab")
		)
		(pad "1" smd custom
			(at 0 -0.4445 180)
			(size 0.1524 0.1524)
			(layers "F.Cu" "F.Mask" "F.Paste")
			(net "VDD_DIFF_2")
			(options
				(clearance outline)
				(anchor circle)
			)
			(primitives
				(gr_poly
					(pts
						(arc
							(start 0.3048 -0.2032)
							(mid 0.275042 -0.275042)
							(end 0.2032 -0.3048)
						)
						(arc
							(start -0.2032 -0.3048)
							(mid -0.275042 -0.275042)
							(end -0.3048 -0.2032)
						)
						(arc
							(start -0.3048 0.2032)
							(mid -0.275042 0.275042)
							(end -0.2032 0.3048)
						)
						(arc
							(start 0.2032 0.3048)
							(mid 0.275042 0.275042)
							(end 0.3048 0.2032)
						)
					)
					(width 0)
					(fill yes)
				)
			)
		)
		(pad "2" smd custom
			(at 0 0.4445 180)
			(size 0.1524 0.1524)
			(layers "F.Cu" "F.Mask" "F.Paste")
			(net "GND")
			(options
				(clearance outline)
				(anchor circle)
			)
			(primitives
				(gr_poly
					(pts
						(arc
							(start 0.3048 -0.2032)
							(mid 0.275042 -0.275042)
							(end 0.2032 -0.3048)
						)
						(arc
							(start -0.2032 -0.3048)
							(mid -0.275042 -0.275042)
							(end -0.3048 -0.2032)
						)
						(arc
							(start -0.3048 0.2032)
							(mid -0.275042 0.275042)
							(end -0.2032 0.3048)
						)
						(arc
							(start 0.2032 0.3048)
							(mid 0.275042 0.275042)
							(end 0.3048 0.2032)
						)
					)
					(width 0)
					(fill yes)
				)
			)
		)
	)
	(footprint ""
		(layer "F.Cu")
		(at 35.56 -410.9974 90)
		(property "Reference" "Q76"
			(at 0 0 90)
			(layer "F.SilkS")
			(hide yes)
			(effects
				(font
					(size 1.27 1.27)
				)
			)
		)
		(property "Value" "2N7002A-7-GP"
			(at 0.127 -8.9662 90)
			(unlocked yes)
			(layer "F.Fab")
			(hide yes)
			(effects
				(font
					(size 1.016 1.016)
					(thickness 0.1524)
				)
			)
		)
		(property "Device Type" "SOT23DGS2D4H48"
			(at 0.127 -10.4902 90)
			(unlocked yes)
			(layer "F.Fab")
			(hide yes)
			(effects
				(font
					(size 1.016 1.016)
					(thickness 0.1524)
				)
			)
		)
		(duplicate_pad_numbers_are_jumpers no)
		(fp_line
			(start 1.651 -1.778)
			(end -1.651 -1.778)
			(stroke
				(width 0.1524)
				(type default)
			)
			(layer "F.SilkS")
		)
		(fp_line
			(start -1.651 -1.778)
			(end -1.651 1.778)
			(stroke
				(width 0.1524)
				(type default)
			)
			(layer "F.SilkS")
		)
		(fp_line
			(start 1.651 1.778)
			(end 1.651 -1.778)
			(stroke
				(width 0.1524)
				(type default)
			)
			(layer "F.SilkS")
		)
		(fp_line
			(start -1.651 1.778)
			(end 1.651 1.778)
			(stroke
				(width 0.1524)
				(type default)
			)
			(layer "F.SilkS")
		)
		(fp_poly
			(pts
				(xy -1.778 1.8796) (xy -1.778 -1.8796) (xy 1.778 -1.8796) (xy 1.778 1.8796)
			)
			(stroke
				(width 0)
				(type default)
			)
			(fill no)
			(layer "F.CrtYd")
		)
		(fp_poly
			(pts
				(xy -1.778 1.8796) (xy -1.778 -1.8796) (xy 1.778 -1.8796) (xy 1.778 1.8796)
			)
			(stroke
				(width 0)
				(type default)
			)
			(fill no)
			(layer "F.Fab")
		)
		(pad "D" smd custom
			(at 0 -0.9525 90)
			(size 0.1905 0.1905)
			(layers "F.Cu" "F.Mask" "F.Paste")
			(net "P12V_MOST10_GATE")
			(options
				(clearance outline)
				(anchor circle)
			)
			(primitives
				(gr_poly
					(pts
						(arc
							(start -0.1778 0.5715)
							(mid -0.321484 0.511984)
							(end -0.381 0.3683)
						)
						(arc
							(start -0.381 -0.3683)
							(mid -0.321484 -0.511984)
							(end -0.1778 -0.5715)
						)
						(arc
							(start 0.1778 -0.5715)
							(mid 0.321484 -0.511984)
							(end 0.381 -0.3683)
						)
						(arc
							(start 0.381 0.3683)
							(mid 0.321484 0.511984)
							(end 0.1778 0.5715)
						)
					)
					(width 0)
					(fill yes)
				)
			)
		)
		(pad "G" smd custom
			(at -0.98425 0.9525 90)
			(size 0.1905 0.1905)
			(layers "F.Cu" "F.Mask" "F.Paste")
			(net "SSD10_PWREN_R")
			(options
				(clearance outline)
				(anchor circle)
			)
			(primitives
				(gr_poly
					(pts
						(arc
							(start -0.1778 0.5715)
							(mid -0.321484 0.511984)
							(end -0.381 0.3683)
						)
						(arc
							(start -0.381 -0.3683)
							(mid -0.321484 -0.511984)
							(end -0.1778 -0.5715)
						)
						(arc
							(start 0.1778 -0.5715)
							(mid 0.321484 -0.511984)
							(end 0.381 -0.3683)
						)
						(arc
							(start 0.381 0.3683)
							(mid 0.321484 0.511984)
							(end 0.1778 0.5715)
						)
					)
					(width 0)
					(fill yes)
				)
			)
		)
		(pad "S" smd custom
			(at 0.98425 0.9525 90)
			(size 0.1905 0.1905)
			(layers "F.Cu" "F.Mask" "F.Paste")
			(net "GND")
			(options
				(clearance outline)
				(anchor circle)
			)
			(primitives
				(gr_poly
					(pts
						(arc
							(start -0.1778 0.5715)
							(mid -0.321484 0.511984)
							(end -0.381 0.3683)
						)
						(arc
							(start -0.381 -0.3683)
							(mid -0.321484 -0.511984)
							(end -0.1778 -0.5715)
						)
						(arc
							(start 0.1778 -0.5715)
							(mid 0.321484 -0.511984)
							(end 0.381 -0.3683)
						)
						(arc
							(start 0.381 0.3683)
							(mid 0.321484 0.511984)
							(end 0.1778 0.5715)
						)
					)
					(width 0)
					(fill yes)
				)
			)
		)
	)
	(footprint ""
		(layer "F.Cu")
		(at 27.0002 -213.6394 180)
		(property "Reference" "PC1251"
			(at 0 0 180)
			(layer "F.SilkS")
			(hide yes)
			(effects
				(font
					(size 1.27 1.27)
				)
			)
		)
		(property "Value" "SC22U25V6KX-GP-U"
			(at -2.860802 -5.279644 180)
			(unlocked yes)
			(layer "F.Fab")
			(hide yes)
			(effects
				(font
					(size 1.016 1.016)
					(thickness 0.1524)
				)
			)
		)
		(property "Device Type" "C1206-TO0D3H75"
			(at -2.860802 -6.803644 180)
			(unlocked yes)
			(layer "F.Fab")
			(hide yes)
			(effects
				(font
					(size 1.016 1.016)
					(thickness 0.1524)
				)
			)
		)
		(duplicate_pad_numbers_are_jumpers no)
		(fp_line
			(start 1.3081 2.3749)
			(end -1.3081 2.3749)
			(stroke
				(width 0.1524)
				(type default)
			)
			(layer "F.SilkS")
		)
		(fp_line
			(start 1.3081 -2.3749)
			(end 1.3081 2.3749)
			(stroke
				(width 0.1524)
				(type default)
			)
			(layer "F.SilkS")
		)
		(fp_line
			(start -1.3081 2.3749)
			(end -1.3081 -2.3749)
			(stroke
				(width 0.1524)
				(type default)
			)
			(layer "F.SilkS")
		)
		(fp_line
			(start -1.3081 -2.3749)
			(end 1.3081 -2.3749)
			(stroke
				(width 0.1524)
				(type default)
			)
			(layer "F.SilkS")
		)
		(fp_rect
			(start -0.8001 1.6002)
			(end 0.8001 -1.6002)
			(stroke
				(width 0)
				(type default)
			)
			(fill no)
			(layer "F.CrtYd")
		)
		(fp_poly
			(pts
				(xy -1.5621 2.4511) (xy -1.5621 1.6002) (xy 0.8001 1.6002) (xy 0.8001 -1.6002) (xy -0.8001 -1.6002)
				(xy -0.8001 1.5875) (xy -1.5621 1.5875) (xy -1.5621 -2.4511) (xy 1.5621 -2.4511) (xy 1.5621 2.4511)
			)
			(stroke
				(width 0)
				(type default)
			)
			(fill no)
			(layer "F.CrtYd")
		)
		(fp_rect
			(start -1.5621 2.4511)
			(end 1.5621 -2.4511)
			(stroke
				(width 0)
				(type default)
			)
			(fill no)
			(layer "F.Fab")
		)
		(pad "1" smd rect
			(at 0 -1.392936 180)
			(size 2.1082 1.4478)
			(layers "F.Cu" "F.Mask" "F.Paste")
			(net "P12V_SSD12")
		)
		(pad "2" smd rect
			(at 0 1.392936 180)
			(size 2.1082 1.4478)
			(layers "F.Cu" "F.Mask" "F.Paste")
			(net "GND")
		)
	)
)
